(kicad_pcb
	(version 20260206)
	(generator "pcbnew")
	(generator_version "10.0")
	(general
		(thickness 1.6)
		(legacy_teardrops no)
	)
	(paper "A4")
	(title_block
		(title "panther-plus-userver — 13130-1b_20150205.brd")
		(comment 1 "Honey Badger (Wiwynn) / footprint 624 of 1509 (DIMM4), pads 170-176 of 210")
	)
	(layers
		(0 "F.Cu" signal "TOP")
		(4 "In1.Cu" signal "L2")
		(6 "In2.Cu" signal "L3")
		(8 "In3.Cu" signal "L4")
		(10 "In4.Cu" signal "L5")
		(12 "In5.Cu" signal "L6")
		(14 "In6.Cu" signal "L7")
		(16 "In7.Cu" signal "L8")
		(18 "In8.Cu" signal "L9")
		(20 "In9.Cu" signal "L10")
		(22 "In10.Cu" signal "L11")
		(2 "B.Cu" signal "BOTTOM")
		(9 "F.Adhes" user "F.Adhesive")
		(11 "B.Adhes" user "B.Adhesive")
		(13 "F.Paste" user "Package Geometry/Pastemask Top")
		(15 "B.Paste" user "Package Geometry/Pastemask Bottom")
		(5 "F.SilkS" user "Ref Des/Silkscreen Top")
		(7 "B.SilkS" user "Ref Des/Silkscreen Bottom")
		(1 "F.Mask" user "Board Geometry/Soldermask Top")
		(3 "B.Mask" user "Board Geometry/Soldermask Bottom")
		(17 "Dwgs.User" user "User.Drawings")
		(19 "Cmts.User" user "User.Comments")
		(21 "Eco1.User" user "User.Eco1")
		(23 "Eco2.User" user "User.Eco2")
		(25 "Edge.Cuts" user "Board Geometry/Outline")
		(27 "Margin" user)
		(31 "F.CrtYd" user "Package Geometry/Place Bound Top")
		(29 "B.CrtYd" user "Package Geometry/Place Bound Bottom")
		(35 "F.Fab" user "Ref Des/Assembly Top")
		(33 "B.Fab" user "Ref Des/Assembly Bottom")
	)
	(footprint ""
		(layer "F.Cu")
		(at 159.999934 -5.790692)
		(property "Reference" "DIMM4"
			(at 0 0 0)
			(layer "F.SilkS")
			(hide yes)
			(effects
				(font
					(size 1.27 1.27)
				)
			)
		)
		(property "Value" "DDR3-204P-174-COLAY-1-GP"
			(at -40.682164 -17.468088 0)
			(unlocked yes)
			(layer "F.Fab")
			(hide yes)
			(effects
				(font
					(size 1.016 1.016)
					(thickness 0.1524)
				)
			)
		)
		(property "Device Type" "AS0A626-H8SN-7H-COLAY-1"
			(at -40.682164 -18.992088 0)
			(unlocked yes)
			(layer "F.Fab")
			(hide yes)
			(effects
				(font
					(size 1.016 1.016)
					(thickness 0.1524)
				)
			)
		)
		(duplicate_pad_numbers_are_jumpers no)
		(pad "168" smd custom
			(at 20.850098 -4.106672)
			(size 0.1143 0.1143)
			(layers "F.Cu" "F.Mask" "F.Paste")
			(net "M_B_DQ49")
			(options
				(clearance outline)
				(anchor circle)
			)
			(primitives
				(gr_poly
					(pts
						(xy 0 0.9017) (xy -0.03175 0.89916) (xy -0.0635 0.889) (xy -0.09144 0.87376) (xy -0.11684 0.85344)
						(xy -0.13716 0.82804) (xy -0.1524 0.8001) (xy -0.16256 0.76835) (xy -0.1651 0.7366) (xy -0.1651 0.19685)
						(xy -0.17272 0.18923) (xy -0.17907 0.18034) (xy -0.18669 0.17145) (xy -0.19177 0.16256) (xy -0.19812 0.15367)
						(xy -0.20828 0.13335) (xy -0.21971 0.10287) (xy -0.22225 0.09271) (xy -0.22479 0.08128) (xy -0.22606 0.07112)
						(xy -0.2286 0.05969) (xy -0.2286 0.01651) (xy -0.22606 0.00508) (xy -0.22479 -0.00508) (xy -0.22225 -0.01651)
						(xy -0.21971 -0.02667) (xy -0.20828 -0.05715) (xy -0.19812 -0.07747) (xy -0.19177 -0.08636) (xy -0.18669 -0.09525)
						(xy -0.17907 -0.10414) (xy -0.17272 -0.11303) (xy -0.1651 -0.12065) (xy -0.1651 -0.7366) (xy -0.16256 -0.76835)
						(xy -0.1524 -0.8001) (xy -0.13716 -0.82804) (xy -0.11684 -0.85344) (xy -0.09144 -0.87376) (xy -0.0635 -0.889)
						(xy -0.03175 -0.89916) (xy 0 -0.9017) (xy 0.03175 -0.89916) (xy 0.0635 -0.889) (xy 0.09144 -0.87376)
						(xy 0.11684 -0.85344) (xy 0.13716 -0.82804) (xy 0.1524 -0.8001) (xy 0.16256 -0.76835) (xy 0.1651 -0.7366)
						(xy 0.1651 -0.11938) (xy 0.17272 -0.11176) (xy 0.19812 -0.0762) (xy 0.2032 -0.06604) (xy 0.20701 -0.05715)
						(xy 0.21209 -0.04699) (xy 0.2159 -0.03683) (xy 0.21844 -0.02667) (xy 0.22225 -0.01524) (xy 0.22352 -0.00508)
						(xy 0.22606 0.00508) (xy 0.22733 0.01651) (xy 0.22733 0.02667) (xy 0.2286 0.0381) (xy 0.22733 0.04953)
						(xy 0.22733 0.05969) (xy 0.22606 0.07112) (xy 0.22352 0.08128) (xy 0.22225 0.09144) (xy 0.21844 0.10287)
						(xy 0.2159 0.11303) (xy 0.21209 0.12319) (xy 0.20701 0.13335) (xy 0.2032 0.14224) (xy 0.19812 0.1524)
						(xy 0.17272 0.18796) (xy 0.1651 0.19558) (xy 0.1651 0.7366) (xy 0.16256 0.76835) (xy 0.1524 0.8001)
						(xy 0.13716 0.82804) (xy 0.11684 0.85344) (xy 0.09144 0.87376) (xy 0.0635 0.889) (xy 0.03175 0.89916)
					)
					(width 0)
					(fill yes)
				)
			)
		)
		(pad "169" smd custom
			(at 21.150072 4.106672)
			(size 0.1143 0.1143)
			(layers "F.Cu" "F.Mask" "F.Paste")
			(net "GND")
			(options
				(clearance outline)
				(anchor circle)
			)
			(primitives
				(gr_poly
					(pts
						(xy 0 0.9017) (xy -0.03175 0.89916) (xy -0.0635 0.889) (xy -0.09144 0.87376) (xy -0.11684 0.85344)
						(xy -0.13716 0.82804) (xy -0.1524 0.8001) (xy -0.16256 0.76835) (xy -0.1651 0.7366) (xy -0.1651 -0.13462)
						(xy -0.17272 -0.14224) (xy -0.19812 -0.1778) (xy -0.2032 -0.18796) (xy -0.20701 -0.19685) (xy -0.21209 -0.20701)
						(xy -0.2159 -0.21717) (xy -0.21844 -0.22733) (xy -0.22225 -0.23876) (xy -0.22352 -0.24892) (xy -0.22606 -0.25908)
						(xy -0.22733 -0.27051) (xy -0.22733 -0.28067) (xy -0.2286 -0.2921) (xy -0.22733 -0.30353) (xy -0.22733 -0.31369)
						(xy -0.22606 -0.32512) (xy -0.22352 -0.33528) (xy -0.22225 -0.34544) (xy -0.21844 -0.35687) (xy -0.2159 -0.36703)
						(xy -0.21209 -0.37719) (xy -0.20701 -0.38735) (xy -0.2032 -0.39624) (xy -0.19812 -0.4064) (xy -0.17272 -0.44196)
						(xy -0.1651 -0.44958) (xy -0.1651 -0.7366) (xy -0.16256 -0.76835) (xy -0.1524 -0.8001) (xy -0.13716 -0.82804)
						(xy -0.11684 -0.85344) (xy -0.09144 -0.87376) (xy -0.0635 -0.889) (xy -0.03175 -0.89916) (xy 0 -0.9017)
						(xy 0.03175 -0.89916) (xy 0.0635 -0.889) (xy 0.09144 -0.87376) (xy 0.11684 -0.85344) (xy 0.13716 -0.82804)
						(xy 0.1524 -0.8001) (xy 0.16256 -0.76835) (xy 0.1651 -0.7366) (xy 0.1651 -0.44958) (xy 0.17272 -0.44196)
						(xy 0.19812 -0.4064) (xy 0.2032 -0.39624) (xy 0.20701 -0.38735) (xy 0.21209 -0.37719) (xy 0.2159 -0.36703)
						(xy 0.21844 -0.35687) (xy 0.22225 -0.34544) (xy 0.22352 -0.33528) (xy 0.22606 -0.32512) (xy 0.22733 -0.31369)
						(xy 0.22733 -0.30353) (xy 0.2286 -0.2921) (xy 0.22733 -0.28067) (xy 0.22733 -0.27051) (xy 0.22606 -0.25908)
						(xy 0.22352 -0.24892) (xy 0.22225 -0.23876) (xy 0.21844 -0.22733) (xy 0.2159 -0.21717) (xy 0.21209 -0.20701)
						(xy 0.20701 -0.19685) (xy 0.2032 -0.18796) (xy 0.19812 -0.1778) (xy 0.17272 -0.14224) (xy 0.1651 -0.13462)
						(xy 0.1651 0.7366) (xy 0.16256 0.76835) (xy 0.1524 0.8001) (xy 0.13716 0.82804) (xy 0.11684 0.85344)
						(xy 0.09144 0.87376) (xy 0.0635 0.889) (xy 0.03175 0.89916)
					)
					(width 0)
					(fill yes)
				)
			)
		)
		(pad "170" smd custom
			(at 21.450046 -4.106672)
			(size 0.1143 0.1143)
			(layers "F.Cu" "F.Mask" "F.Paste")
			(net "GND")
			(options
				(clearance outline)
				(anchor circle)
			)
			(primitives
				(gr_poly
					(pts
						(xy 0 0.9017) (xy -0.03175 0.89916) (xy -0.0635 0.889) (xy -0.09144 0.87376) (xy -0.11684 0.85344)
						(xy -0.13716 0.82804) (xy -0.1524 0.8001) (xy -0.16256 0.76835) (xy -0.1651 0.7366) (xy -0.1651 0.44958)
						(xy -0.17272 0.44196) (xy -0.19812 0.4064) (xy -0.2032 0.39624) (xy -0.20701 0.38735) (xy -0.21209 0.37719)
						(xy -0.2159 0.36703) (xy -0.21844 0.35687) (xy -0.22225 0.34544) (xy -0.22352 0.33528) (xy -0.22606 0.32512)
						(xy -0.22733 0.31369) (xy -0.22733 0.30353) (xy -0.2286 0.2921) (xy -0.22733 0.28067) (xy -0.22733 0.27051)
						(xy -0.22606 0.25908) (xy -0.22352 0.24892) (xy -0.22225 0.23876) (xy -0.21844 0.22733) (xy -0.2159 0.21717)
						(xy -0.21209 0.20701) (xy -0.20701 0.19685) (xy -0.2032 0.18796) (xy -0.19812 0.1778) (xy -0.17272 0.14224)
						(xy -0.1651 0.13462) (xy -0.1651 -0.7366) (xy -0.16256 -0.76835) (xy -0.1524 -0.8001) (xy -0.13716 -0.82804)
						(xy -0.11684 -0.85344) (xy -0.09144 -0.87376) (xy -0.0635 -0.889) (xy -0.03175 -0.89916) (xy 0 -0.9017)
						(xy 0.03175 -0.89916) (xy 0.0635 -0.889) (xy 0.09144 -0.87376) (xy 0.11684 -0.85344) (xy 0.13716 -0.82804)
						(xy 0.1524 -0.8001) (xy 0.16256 -0.76835) (xy 0.1651 -0.7366) (xy 0.1651 0.13462) (xy 0.17272 0.14224)
						(xy 0.19812 0.1778) (xy 0.2032 0.18796) (xy 0.20701 0.19685) (xy 0.21209 0.20701) (xy 0.2159 0.21717)
						(xy 0.21844 0.22733) (xy 0.22225 0.23876) (xy 0.22352 0.24892) (xy 0.22606 0.25908) (xy 0.22733 0.27051)
						(xy 0.22733 0.28067) (xy 0.2286 0.2921) (xy 0.22733 0.30353) (xy 0.22733 0.31369) (xy 0.22606 0.32512)
						(xy 0.22352 0.33528) (xy 0.22225 0.34544) (xy 0.21844 0.35687) (xy 0.2159 0.36703) (xy 0.21209 0.37719)
						(xy 0.20701 0.38735) (xy 0.2032 0.39624) (xy 0.19812 0.4064) (xy 0.17272 0.44196) (xy 0.1651 0.44958)
						(xy 0.1651 0.7366) (xy 0.16256 0.76835) (xy 0.1524 0.8001) (xy 0.13716 0.82804) (xy 0.11684 0.85344)
						(xy 0.09144 0.87376) (xy 0.0635 0.889) (xy 0.03175 0.89916)
					)
					(width 0)
					(fill yes)
				)
			)
		)
		(pad "171" smd custom
			(at 21.75002 4.106672)
			(size 0.1143 0.1143)
			(layers "F.Cu" "F.Mask" "F.Paste")
			(net "M_B_DQS_DN6")
			(options
				(clearance outline)
				(anchor circle)
			)
			(primitives
				(gr_poly
					(pts
						(xy 0 0.9017) (xy -0.03175 0.89916) (xy -0.0635 0.889) (xy -0.09144 0.87376) (xy -0.11684 0.85344)
						(xy -0.13716 0.82804) (xy -0.1524 0.8001) (xy -0.16256 0.76835) (xy -0.1651 0.7366) (xy -0.1651 0.11938)
						(xy -0.17272 0.11176) (xy -0.19812 0.0762) (xy -0.2032 0.06604) (xy -0.20701 0.05715) (xy -0.21209 0.04699)
						(xy -0.2159 0.03683) (xy -0.21844 0.02667) (xy -0.22225 0.01524) (xy -0.22352 0.00508) (xy -0.22606 -0.00508)
						(xy -0.22733 -0.01651) (xy -0.22733 -0.02667) (xy -0.2286 -0.0381) (xy -0.22733 -0.04953) (xy -0.22733 -0.05969)
						(xy -0.22606 -0.07112) (xy -0.22352 -0.08128) (xy -0.22225 -0.09144) (xy -0.21844 -0.10287) (xy -0.2159 -0.11303)
						(xy -0.21209 -0.12319) (xy -0.20701 -0.13335) (xy -0.2032 -0.14224) (xy -0.19812 -0.1524) (xy -0.17272 -0.18796)
						(xy -0.1651 -0.19558) (xy -0.1651 -0.7366) (xy -0.16256 -0.76835) (xy -0.1524 -0.8001) (xy -0.13716 -0.82804)
						(xy -0.11684 -0.85344) (xy -0.09144 -0.87376) (xy -0.0635 -0.889) (xy -0.03175 -0.89916) (xy 0 -0.9017)
						(xy 0.03175 -0.89916) (xy 0.0635 -0.889) (xy 0.09144 -0.87376) (xy 0.11684 -0.85344) (xy 0.13716 -0.82804)
						(xy 0.1524 -0.8001) (xy 0.16256 -0.76835) (xy 0.1651 -0.7366) (xy 0.1651 -0.19685) (xy 0.17272 -0.18923)
						(xy 0.17907 -0.18034) (xy 0.18669 -0.17145) (xy 0.19177 -0.16256) (xy 0.19812 -0.15367) (xy 0.20828 -0.13335)
						(xy 0.21971 -0.10287) (xy 0.22225 -0.09271) (xy 0.22479 -0.08128) (xy 0.22606 -0.07112) (xy 0.2286 -0.05969)
						(xy 0.2286 -0.01651) (xy 0.22606 -0.00508) (xy 0.22479 0.00508) (xy 0.22225 0.01651) (xy 0.21971 0.02667)
						(xy 0.20828 0.05715) (xy 0.19812 0.07747) (xy 0.19177 0.08636) (xy 0.18669 0.09525) (xy 0.17907 0.10414)
						(xy 0.17272 0.11303) (xy 0.1651 0.12065) (xy 0.1651 0.7366) (xy 0.16256 0.76835) (xy 0.1524 0.8001)
						(xy 0.13716 0.82804) (xy 0.11684 0.85344) (xy 0.09144 0.87376) (xy 0.0635 0.889) (xy 0.03175 0.89916)
					)
					(width 0)
					(fill yes)
				)
			)
		)
		(pad "172" smd custom
			(at 22.049994 -4.106672)
			(size 0.1143 0.1143)
			(layers "F.Cu" "F.Mask" "F.Paste")
			(net "GND")
			(options
				(clearance outline)
				(anchor circle)
			)
			(primitives
				(gr_poly
					(pts
						(xy 0 0.9017) (xy -0.03175 0.89916) (xy -0.0635 0.889) (xy -0.09144 0.87376) (xy -0.11684 0.85344)
						(xy -0.13716 0.82804) (xy -0.1524 0.8001) (xy -0.16256 0.76835) (xy -0.1651 0.7366) (xy -0.1651 0.19685)
						(xy -0.17272 0.18923) (xy -0.17907 0.18034) (xy -0.18669 0.17145) (xy -0.19177 0.16256) (xy -0.19812 0.15367)
						(xy -0.20828 0.13335) (xy -0.21971 0.10287) (xy -0.22225 0.09271) (xy -0.22479 0.08128) (xy -0.22606 0.07112)
						(xy -0.2286 0.05969) (xy -0.2286 0.01651) (xy -0.22606 0.00508) (xy -0.22479 -0.00508) (xy -0.22225 -0.01651)
						(xy -0.21971 -0.02667) (xy -0.20828 -0.05715) (xy -0.19812 -0.07747) (xy -0.19177 -0.08636) (xy -0.18669 -0.09525)
						(xy -0.17907 -0.10414) (xy -0.17272 -0.11303) (xy -0.1651 -0.12065) (xy -0.1651 -0.7366) (xy -0.16256 -0.76835)
						(xy -0.1524 -0.8001) (xy -0.13716 -0.82804) (xy -0.11684 -0.85344) (xy -0.09144 -0.87376) (xy -0.0635 -0.889)
						(xy -0.03175 -0.89916) (xy 0 -0.9017) (xy 0.03175 -0.89916) (xy 0.0635 -0.889) (xy 0.09144 -0.87376)
						(xy 0.11684 -0.85344) (xy 0.13716 -0.82804) (xy 0.1524 -0.8001) (xy 0.16256 -0.76835) (xy 0.1651 -0.7366)
						(xy 0.1651 -0.11938) (xy 0.17272 -0.11176) (xy 0.19812 -0.0762) (xy 0.2032 -0.06604) (xy 0.20701 -0.05715)
						(xy 0.21209 -0.04699) (xy 0.2159 -0.03683) (xy 0.21844 -0.02667) (xy 0.22225 -0.01524) (xy 0.22352 -0.00508)
						(xy 0.22606 0.00508) (xy 0.22733 0.01651) (xy 0.22733 0.02667) (xy 0.2286 0.0381) (xy 0.22733 0.04953)
						(xy 0.22733 0.05969) (xy 0.22606 0.07112) (xy 0.22352 0.08128) (xy 0.22225 0.09144) (xy 0.21844 0.10287)
						(xy 0.2159 0.11303) (xy 0.21209 0.12319) (xy 0.20701 0.13335) (xy 0.2032 0.14224) (xy 0.19812 0.1524)
						(xy 0.17272 0.18796) (xy 0.1651 0.19558) (xy 0.1651 0.7366) (xy 0.16256 0.76835) (xy 0.1524 0.8001)
						(xy 0.13716 0.82804) (xy 0.11684 0.85344) (xy 0.09144 0.87376) (xy 0.0635 0.889) (xy 0.03175 0.89916)
					)
					(width 0)
					(fill yes)
				)
			)
		)
		(pad "173" smd custom
			(at 22.349968 4.106672)
			(size 0.1143 0.1143)
			(layers "F.Cu" "F.Mask" "F.Paste")
			(net "M_B_DQS_DP6")
			(options
				(clearance outline)
				(anchor circle)
			)
			(primitives
				(gr_poly
					(pts
						(xy 0 0.9017) (xy -0.03175 0.89916) (xy -0.0635 0.889) (xy -0.09144 0.87376) (xy -0.11684 0.85344)
						(xy -0.13716 0.82804) (xy -0.1524 0.8001) (xy -0.16256 0.76835) (xy -0.1651 0.7366) (xy -0.1651 -0.13462)
						(xy -0.17272 -0.14224) (xy -0.19812 -0.1778) (xy -0.2032 -0.18796) (xy -0.20701 -0.19685) (xy -0.21209 -0.20701)
						(xy -0.2159 -0.21717) (xy -0.21844 -0.22733) (xy -0.22225 -0.23876) (xy -0.22352 -0.24892) (xy -0.22606 -0.25908)
						(xy -0.22733 -0.27051) (xy -0.22733 -0.28067) (xy -0.2286 -0.2921) (xy -0.22733 -0.30353) (xy -0.22733 -0.31369)
						(xy -0.22606 -0.32512) (xy -0.22352 -0.33528) (xy -0.22225 -0.34544) (xy -0.21844 -0.35687) (xy -0.2159 -0.36703)
						(xy -0.21209 -0.37719) (xy -0.20701 -0.38735) (xy -0.2032 -0.39624) (xy -0.19812 -0.4064) (xy -0.17272 -0.44196)
						(xy -0.1651 -0.44958) (xy -0.1651 -0.7366) (xy -0.16256 -0.76835) (xy -0.1524 -0.8001) (xy -0.13716 -0.82804)
						(xy -0.11684 -0.85344) (xy -0.09144 -0.87376) (xy -0.0635 -0.889) (xy -0.03175 -0.89916) (xy 0 -0.9017)
						(xy 0.03175 -0.89916) (xy 0.0635 -0.889) (xy 0.09144 -0.87376) (xy 0.11684 -0.85344) (xy 0.13716 -0.82804)
						(xy 0.1524 -0.8001) (xy 0.16256 -0.76835) (xy 0.1651 -0.7366) (xy 0.1651 -0.44958) (xy 0.17272 -0.44196)
						(xy 0.19812 -0.4064) (xy 0.2032 -0.39624) (xy 0.20701 -0.38735) (xy 0.21209 -0.37719) (xy 0.2159 -0.36703)
						(xy 0.21844 -0.35687) (xy 0.22225 -0.34544) (xy 0.22352 -0.33528) (xy 0.22606 -0.32512) (xy 0.22733 -0.31369)
						(xy 0.22733 -0.30353) (xy 0.2286 -0.2921) (xy 0.22733 -0.28067) (xy 0.22733 -0.27051) (xy 0.22606 -0.25908)
						(xy 0.22352 -0.24892) (xy 0.22225 -0.23876) (xy 0.21844 -0.22733) (xy 0.2159 -0.21717) (xy 0.21209 -0.20701)
						(xy 0.20701 -0.19685) (xy 0.2032 -0.18796) (xy 0.19812 -0.1778) (xy 0.17272 -0.14224) (xy 0.1651 -0.13462)
						(xy 0.1651 0.7366) (xy 0.16256 0.76835) (xy 0.1524 0.8001) (xy 0.13716 0.82804) (xy 0.11684 0.85344)
						(xy 0.09144 0.87376) (xy 0.0635 0.889) (xy 0.03175 0.89916)
					)
					(width 0)
					(fill yes)
				)
			)
		)
		(pad "174" smd custom
			(at 22.649942 -4.106672)
			(size 0.1143 0.1143)
			(layers "F.Cu" "F.Mask" "F.Paste")
			(net "M_B_DQ50")
			(options
				(clearance outline)
				(anchor circle)
			)
			(primitives
				(gr_poly
					(pts
						(xy 0 0.9017) (xy -0.03175 0.89916) (xy -0.0635 0.889) (xy -0.09144 0.87376) (xy -0.11684 0.85344)
						(xy -0.13716 0.82804) (xy -0.1524 0.8001) (xy -0.16256 0.76835) (xy -0.1651 0.7366) (xy -0.1651 0.44958)
						(xy -0.17272 0.44196) (xy -0.19812 0.4064) (xy -0.2032 0.39624) (xy -0.20701 0.38735) (xy -0.21209 0.37719)
						(xy -0.2159 0.36703) (xy -0.21844 0.35687) (xy -0.22225 0.34544) (xy -0.22352 0.33528) (xy -0.22606 0.32512)
						(xy -0.22733 0.31369) (xy -0.22733 0.30353) (xy -0.2286 0.2921) (xy -0.22733 0.28067) (xy -0.22733 0.27051)
						(xy -0.22606 0.25908) (xy -0.22352 0.24892) (xy -0.22225 0.23876) (xy -0.21844 0.22733) (xy -0.2159 0.21717)
						(xy -0.21209 0.20701) (xy -0.20701 0.19685) (xy -0.2032 0.18796) (xy -0.19812 0.1778) (xy -0.17272 0.14224)
						(xy -0.1651 0.13462) (xy -0.1651 -0.7366) (xy -0.16256 -0.76835) (xy -0.1524 -0.8001) (xy -0.13716 -0.82804)
						(xy -0.11684 -0.85344) (xy -0.09144 -0.87376) (xy -0.0635 -0.889) (xy -0.03175 -0.89916) (xy 0 -0.9017)
						(xy 0.03175 -0.89916) (xy 0.0635 -0.889) (xy 0.09144 -0.87376) (xy 0.11684 -0.85344) (xy 0.13716 -0.82804)
						(xy 0.1524 -0.8001) (xy 0.16256 -0.76835) (xy 0.1651 -0.7366) (xy 0.1651 0.13462) (xy 0.17272 0.14224)
						(xy 0.19812 0.1778) (xy 0.2032 0.18796) (xy 0.20701 0.19685) (xy 0.21209 0.20701) (xy 0.2159 0.21717)
						(xy 0.21844 0.22733) (xy 0.22225 0.23876) (xy 0.22352 0.24892) (xy 0.22606 0.25908) (xy 0.22733 0.27051)
						(xy 0.22733 0.28067) (xy 0.2286 0.2921) (xy 0.22733 0.30353) (xy 0.22733 0.31369) (xy 0.22606 0.32512)
						(xy 0.22352 0.33528) (xy 0.22225 0.34544) (xy 0.21844 0.35687) (xy 0.2159 0.36703) (xy 0.21209 0.37719)
						(xy 0.20701 0.38735) (xy 0.2032 0.39624) (xy 0.19812 0.4064) (xy 0.17272 0.44196) (xy 0.1651 0.44958)
						(xy 0.1651 0.7366) (xy 0.16256 0.76835) (xy 0.1524 0.8001) (xy 0.13716 0.82804) (xy 0.11684 0.85344)
						(xy 0.09144 0.87376) (xy 0.0635 0.889) (xy 0.03175 0.89916)
					)
					(width 0)
					(fill yes)
				)
			)
		)
	)
)
